(kicad_pcb
	(version 20260206)
	(generator "pcbnew")
	(generator_version "10.0")
	(general
		(thickness 1.6)
		(legacy_teardrops no)
	)
	(paper "A4")
	(title_block
		(title "03242023_DA0F0TMBIJ0_F0T_Motherboard_J_brd_V01_OCP.brd")
		(comment 1 "Grand Teton / footprints 4012-4016 of 6105")
	)
	(layers
		(0 "F.Cu" signal "TOP")
		(4 "In1.Cu" signal "GND")
		(6 "In2.Cu" signal "IN1")
		(8 "In3.Cu" signal "GND1")
		(10 "In4.Cu" signal "IN2")
		(12 "In5.Cu" signal "GND2")
		(14 "In6.Cu" signal "IN3")
		(16 "In7.Cu" signal "GND3")
		(18 "In8.Cu" signal "VCC")
		(20 "In9.Cu" signal "VCC1")
		(22 "In10.Cu" signal "GND4")
		(24 "In11.Cu" signal "IN4")
		(26 "In12.Cu" signal "GND5")
		(28 "In13.Cu" signal "IN5")
		(30 "In14.Cu" signal "GND6")
		(32 "In15.Cu" signal "IN6")
		(34 "In16.Cu" signal "GND7")
		(2 "B.Cu" signal "BOTTOM")
		(9 "F.Adhes" user "F.Adhesive")
		(11 "B.Adhes" user "B.Adhesive")
		(13 "F.Paste" user "Package Geometry/Pastemask Top")
		(15 "B.Paste" user "Package Geometry/Pastemask Bottom")
		(5 "F.SilkS" user "Ref Des/Silkscreen Top")
		(7 "B.SilkS" user "Ref Des/Silkscreen Bottom")
		(1 "F.Mask" user "Board Geometry/Soldermask Top")
		(3 "B.Mask" user "Board Geometry/Soldermask Bottom")
		(17 "Dwgs.User" user "User.Drawings")
		(19 "Cmts.User" user "User.Comments")
		(21 "Eco1.User" user "User.Eco1")
		(23 "Eco2.User" user "User.Eco2")
		(25 "Edge.Cuts" user "Board Geometry/Outline")
		(27 "Margin" user)
		(31 "F.CrtYd" user "Package Geometry/Place Bound Top")
		(29 "B.CrtYd" user "Package Geometry/Place Bound Bottom")
		(35 "F.Fab" user "Ref Des/Assembly Top")
		(33 "B.Fab" user "Ref Des/Assembly Bottom")
	)
	(footprint ""
		(layer "F.Cu")
		(at 54.89956 -147.84197 90)
		(property "Reference" "PU51_P1_2"
			(at -5.795772 -4.134358 0)
			(unlocked yes)
			(layer "F.SilkS")
			(effects
				(font
					(size 0.7874 0.5842)
					(thickness 0.1524)
				)
				(justify left)
			)
		)
		(property "Value" ""
			(at 0 0 90)
			(layer "F.Fab")
			(effects
				(font
					(size 1.27 1.27)
				)
			)
		)
		(duplicate_pad_numbers_are_jumpers no)
		(fp_line
			(start 2.500122 -2.999994)
			(end 2.500122 -2.44348)
			(stroke
				(width 0.1524)
				(type default)
			)
			(layer "F.SilkS")
		)
		(fp_line
			(start 2.31394 -2.999994)
			(end 2.500122 -2.999994)
			(stroke
				(width 0.1524)
				(type default)
			)
			(layer "F.SilkS")
		)
		(fp_line
			(start -2.500122 -2.999994)
			(end -2.24409 -2.999994)
			(stroke
				(width 0.1524)
				(type default)
			)
			(layer "F.SilkS")
		)
		(fp_line
			(start -2.500122 -2.529078)
			(end -2.500122 -2.999994)
			(stroke
				(width 0.1524)
				(type default)
			)
			(layer "F.SilkS")
		)
		(fp_line
			(start -2.500122 0.6604)
			(end -2.500122 0.229108)
			(stroke
				(width 0.1524)
				(type default)
			)
			(layer "F.SilkS")
		)
		(fp_line
			(start 2.500122 2.339594)
			(end 2.500122 2.999994)
			(stroke
				(width 0.1524)
				(type default)
			)
			(layer "F.SilkS")
		)
		(fp_line
			(start 2.500122 2.999994)
			(end 2.2987 2.999994)
			(stroke
				(width 0.1524)
				(type default)
			)
			(layer "F.SilkS")
		)
		(fp_line
			(start -2.2987 2.999994)
			(end -2.500122 2.999994)
			(stroke
				(width 0.1524)
				(type default)
			)
			(layer "F.SilkS")
		)
		(fp_line
			(start -2.500122 2.999994)
			(end -2.500122 2.339594)
			(stroke
				(width 0.1524)
				(type default)
			)
			(layer "F.SilkS")
		)
		(fp_poly
			(pts
				(xy -5.099812 -2.818638) (xy -4.083812 -2.310638) (xy -5.099812 -1.802638)
			)
			(stroke
				(width 0)
				(type default)
			)
			(fill yes)
			(layer "F.SilkS")
		)
		(fp_line
			(start 2.500122 -2.999994)
			(end 2.500122 2.999994)
			(stroke
				(width 0.1)
				(type default)
			)
			(layer "F.Fab")
		)
		(fp_line
			(start -2.500122 -2.999994)
			(end 2.500122 -2.999994)
			(stroke
				(width 0.1)
				(type default)
			)
			(layer "F.Fab")
		)
		(fp_line
			(start 2.500122 2.999994)
			(end -2.500122 2.999994)
			(stroke
				(width 0.1)
				(type default)
			)
			(layer "F.Fab")
		)
		(fp_line
			(start -2.500122 2.999994)
			(end -2.500122 -2.999994)
			(stroke
				(width 0.1)
				(type default)
			)
			(layer "F.Fab")
		)
		(fp_poly
			(pts
				(xy -4.218432 -2.783078) (xy -4.218432 -1.767078) (xy -3.202432 -2.275078)
			)
			(stroke
				(width 0)
				(type default)
			)
			(fill yes)
			(layer "F.Fab")
		)
		(pad "1" smd rect
			(at -2.400046 -2.275078 180)
			(size 0.2286 0.6096)
			(layers "F.Cu" "F.Mask" "F.Paste")
			(net "PVCCINFAON_CPU1_VOS2")
		)
		(pad "2" smd rect
			(at -2.400046 -1.82499 180)
			(size 0.2286 0.6096)
			(layers "F.Cu" "F.Mask" "F.Paste")
			(net "GND")
		)
		(pad "3" smd rect
			(at -2.400046 -1.374902 180)
			(size 0.2286 0.6096)
			(layers "F.Cu" "F.Mask" "F.Paste")
			(net "PVCCINFAON_CPU1_VDD2")
		)
		(pad "4" smd rect
			(at -2.400046 -0.925068 180)
			(size 0.2286 0.6096)
			(layers "F.Cu" "F.Mask" "F.Paste")
			(net "PVCCFA_EHV_CPU1_PVCC")
		)
		(pad "5" smd rect
			(at -2.400046 -0.47498 180)
			(size 0.2286 0.6096)
			(layers "F.Cu" "F.Mask" "F.Paste")
			(net "GND")
		)
		(pad "6" smd rect
			(at -2.400046 -0.024892 180)
			(size 0.2286 0.6096)
			(layers "F.Cu" "F.Mask" "F.Paste")
			(net "Net_1932")
		)
		(pad "7_9-20_24" smd circle
			(at 0 1.150112 180)
			(size 0 0)
			(layers "F.Cu" "F.Mask" "F.Paste")
			(net "GND")
		)
		(pad "10_19" smd rect
			(at 0 2.899918 180)
			(size 0.6096 4.318)
			(layers "F.Cu" "F.Mask" "F.Paste")
			(net "SW_PVCCINFAON_CPU1_SW2")
		)
		(pad "25_29" smd rect
			(at 1.549908 -1.279906)
			(size 2.0574 2.3114)
			(layers "F.Cu" "F.Mask" "F.Paste")
			(net "SW_P12V_PVCCINFAON_CPU1_FLT")
		)
		(pad "30" smd rect
			(at 2.05994 -2.899918 90)
			(size 0.2286 0.6096)
			(layers "F.Cu" "F.Mask" "F.Paste")
			(net "SW_P12V_PVCCINFAON_CPU1_FLT")
		)
		(pad "31" smd rect
			(at 1.610106 -2.899918 90)
			(size 0.2286 0.6096)
			(layers "F.Cu" "F.Mask" "F.Paste")
			(net "Net_1931")
		)
		(pad "32" smd rect
			(at 1.160018 -2.899918 90)
			(size 0.2286 0.6096)
			(layers "F.Cu" "F.Mask" "F.Paste")
			(net "SW_PVCCINFAON_CPU1_BOOTR2")
		)
		(pad "33" smd rect
			(at 0.70993 -2.899918 90)
			(size 0.2286 0.6096)
			(layers "F.Cu" "F.Mask" "F.Paste")
			(net "SW_PVCCINFAON_CPU1_BOOT2")
		)
		(pad "34" smd rect
			(at 0.260096 -2.899918 90)
			(size 0.2286 0.6096)
			(layers "F.Cu" "F.Mask" "F.Paste")
			(net "PVCCINFAON_CPU1_APWM2")
		)
		(pad "35" smd rect
			(at -0.189992 -2.899918 90)
			(size 0.2286 0.6096)
			(layers "F.Cu" "F.Mask" "F.Paste")
			(net "PVCCINFAON_CPU1_VDD2")
		)
		(pad "36" smd rect
			(at -0.64008 -2.899918 90)
			(size 0.2286 0.6096)
			(layers "F.Cu" "F.Mask" "F.Paste")
			(net "PVCCINFAON_CPU1_ATSEN")
		)
		(pad "37" smd rect
			(at -1.089914 -2.899918 90)
			(size 0.2286 0.6096)
			(layers "F.Cu" "F.Mask" "F.Paste")
			(net "PVCCINFAON_CPU1_LSET2")
		)
		(pad "38" smd rect
			(at -1.540002 -2.899918 90)
			(size 0.2286 0.6096)
			(layers "F.Cu" "F.Mask" "F.Paste")
			(net "PVCCINFAON_CPU1_ACSP2")
		)
		(pad "39" smd rect
			(at -1.99009 -2.899918 90)
			(size 0.2286 0.6096)
			(layers "F.Cu" "F.Mask" "F.Paste")
			(net "PVCCINFAON_CPU1_VREF")
		)
		(pad "40" smd rect
			(at -0.87503 -1.27508 90)
			(size 1.7526 1.9558)
			(layers "F.Cu" "F.Mask" "F.Paste")
			(net "GND")
		)
		(pad "41" smd rect
			(at -1.525016 0.249936)
			(size 0.3048 0.4572)
			(layers "F.Cu" "F.Mask" "F.Paste")
			(net "Net_1933")
		)
		(zone
			(layer "F.Cu")
			(hatch none 0.5)
			(connect_pads
				(clearance 0)
			)
			(min_thickness 0.25)
			(keepout
				(tracks not_allowed)
				(vias allowed)
				(pads allowed)
				(copperpour not_allowed)
				(footprints allowed)
			)
			(placement
				(enabled no)
				(sheetname "")
			)
			(fill
				(thermal_gap 0.5)
				(thermal_bridge_width 0.5)
				(island_removal_mode 0)
			)
			(polygon
				(pts
					(xy 53.19268 -146.03984) (xy 54.3052 -146.03984) (xy 54.3052 -145.797524) (xy 53.19268 -145.797524)
				)
			)
		)
		(zone
			(layer "F.Cu")
			(hatch none 0.5)
			(connect_pads
				(clearance 0)
			)
			(min_thickness 0.25)
			(keepout
				(tracks not_allowed)
				(vias allowed)
				(pads allowed)
				(copperpour not_allowed)
				(footprints allowed)
			)
			(placement
				(enabled no)
				(sheetname "")
			)
			(fill
				(thermal_gap 0.5)
				(thermal_bridge_width 0.5)
				(island_removal_mode 0)
			)
			(polygon
				(pts
					(xy 57.899554 -145.341848) (xy 57.3786 -145.341848) (xy 57.150254 -145.570194) (xy 57.150254 -150.139146)
					(xy 57.3532 -150.342092) (xy 57.899554 -150.342092) (xy 57.899554 -150.05177) (xy 57.443878 -150.05177)
					(xy 57.443878 -145.63217) (xy 57.899554 -145.63217)
				)
			)
		)
	)
	(footprint ""
		(layer "F.Cu")
		(at 63.575438 -31.887922 90)
		(property "Reference" "PR3849"
			(at 0 0 90)
			(layer "F.SilkS")
			(hide yes)
			(effects
				(font
					(size 1.27 1.27)
				)
			)
		)
		(property "Value" ""
			(at 0 0 90)
			(layer "F.Fab")
			(effects
				(font
					(size 1.27 1.27)
				)
			)
		)
		(duplicate_pad_numbers_are_jumpers no)
		(fp_line
			(start 0.7874 -0.4064)
			(end 0.7874 0.4064)
			(stroke
				(width 0.1524)
				(type default)
			)
			(layer "F.SilkS")
		)
		(fp_line
			(start -0.7874 -0.4064)
			(end 0.7874 -0.4064)
			(stroke
				(width 0.1524)
				(type default)
			)
			(layer "F.SilkS")
		)
		(fp_line
			(start 0.7874 0.4064)
			(end -0.7874 0.4064)
			(stroke
				(width 0.1524)
				(type default)
			)
			(layer "F.SilkS")
		)
		(fp_line
			(start -0.7874 0.4064)
			(end -0.7874 -0.4064)
			(stroke
				(width 0.1524)
				(type default)
			)
			(layer "F.SilkS")
		)
		(fp_line
			(start -0.12065 -0.305054)
			(end -0.12065 -0.2794)
			(stroke
				(width 0.1)
				(type default)
			)
			(layer "F.Fab")
		)
		(fp_line
			(start -0.67945 -0.305054)
			(end -0.12065 -0.305054)
			(stroke
				(width 0.1)
				(type default)
			)
			(layer "F.Fab")
		)
		(fp_line
			(start 0.67945 -0.3048)
			(end 0.67945 0.3048)
			(stroke
				(width 0.1)
				(type default)
			)
			(layer "F.Fab")
		)
		(fp_line
			(start 0.12065 -0.3048)
			(end 0.67945 -0.3048)
			(stroke
				(width 0.1)
				(type default)
			)
			(layer "F.Fab")
		)
		(fp_line
			(start 0.12065 -0.2794)
			(end 0.12065 -0.3048)
			(stroke
				(width 0.1)
				(type default)
			)
			(layer "F.Fab")
		)
		(fp_line
			(start -0.12065 -0.2794)
			(end 0.12065 -0.2794)
			(stroke
				(width 0.1)
				(type default)
			)
			(layer "F.Fab")
		)
		(fp_line
			(start 0.120396 0.2794)
			(end -0.12065 0.2794)
			(stroke
				(width 0.1)
				(type default)
			)
			(layer "F.Fab")
		)
		(fp_line
			(start -0.12065 0.2794)
			(end -0.12065 0.3048)
			(stroke
				(width 0.1)
				(type default)
			)
			(layer "F.Fab")
		)
		(fp_line
			(start 0.67945 0.3048)
			(end 0.120396 0.3048)
			(stroke
				(width 0.1)
				(type default)
			)
			(layer "F.Fab")
		)
		(fp_line
			(start 0.120396 0.3048)
			(end 0.120396 0.2794)
			(stroke
				(width 0.1)
				(type default)
			)
			(layer "F.Fab")
		)
		(fp_line
			(start -0.12065 0.3048)
			(end -0.67945 0.3048)
			(stroke
				(width 0.1)
				(type default)
			)
			(layer "F.Fab")
		)
		(fp_line
			(start -0.67945 0.3048)
			(end -0.67945 -0.305054)
			(stroke
				(width 0.1)
				(type default)
			)
			(layer "F.Fab")
		)
		(pad "1" smd circle
			(at -0.40005 0 90)
			(size 0 0)
			(layers "F.Cu" "F.Mask" "F.Paste")
			(net "P12V_OCP_IMON_2")
		)
		(pad "2" smd circle
			(at 0.40005 0 90)
			(size 0 0)
			(layers "F.Cu" "F.Mask" "F.Paste")
			(net "GND")
		)
	)
	(footprint ""
		(layer "F.Cu")
		(at 430.600104 -138.558778 180)
		(property "Reference" "R2389"
			(at 0 0 180)
			(layer "F.SilkS")
			(hide yes)
			(effects
				(font
					(size 1.27 1.27)
				)
			)
		)
		(property "Value" ""
			(at 0 0 180)
			(layer "F.Fab")
			(effects
				(font
					(size 1.27 1.27)
				)
			)
		)
		(duplicate_pad_numbers_are_jumpers no)
		(fp_line
			(start 0.7874 0.4064)
			(end -0.7874 0.4064)
			(stroke
				(width 0.1524)
				(type default)
			)
			(layer "F.SilkS")
		)
		(fp_line
			(start 0.7874 -0.4064)
			(end 0.7874 0.4064)
			(stroke
				(width 0.1524)
				(type default)
			)
			(layer "F.SilkS")
		)
		(fp_line
			(start -0.7874 0.4064)
			(end -0.7874 -0.4064)
			(stroke
				(width 0.1524)
				(type default)
			)
			(layer "F.SilkS")
		)
		(fp_line
			(start -0.7874 -0.4064)
			(end 0.7874 -0.4064)
			(stroke
				(width 0.1524)
				(type default)
			)
			(layer "F.SilkS")
		)
		(fp_line
			(start 0.67945 0.3048)
			(end 0.120396 0.3048)
			(stroke
				(width 0.1)
				(type default)
			)
			(layer "F.Fab")
		)
		(fp_line
			(start 0.67945 -0.3048)
			(end 0.67945 0.3048)
			(stroke
				(width 0.1)
				(type default)
			)
			(layer "F.Fab")
		)
		(fp_line
			(start 0.12065 -0.2794)
			(end 0.12065 -0.3048)
			(stroke
				(width 0.1)
				(type default)
			)
			(layer "F.Fab")
		)
		(fp_line
			(start 0.12065 -0.3048)
			(end 0.67945 -0.3048)
			(stroke
				(width 0.1)
				(type default)
			)
			(layer "F.Fab")
		)
		(fp_line
			(start 0.120396 0.3048)
			(end 0.120396 0.2794)
			(stroke
				(width 0.1)
				(type default)
			)
			(layer "F.Fab")
		)
		(fp_line
			(start 0.120396 0.2794)
			(end -0.12065 0.2794)
			(stroke
				(width 0.1)
				(type default)
			)
			(layer "F.Fab")
		)
		(fp_line
			(start -0.12065 0.3048)
			(end -0.67945 0.3048)
			(stroke
				(width 0.1)
				(type default)
			)
			(layer "F.Fab")
		)
		(fp_line
			(start -0.12065 0.2794)
			(end -0.12065 0.3048)
			(stroke
				(width 0.1)
				(type default)
			)
			(layer "F.Fab")
		)
		(fp_line
			(start -0.12065 -0.2794)
			(end 0.12065 -0.2794)
			(stroke
				(width 0.1)
				(type default)
			)
			(layer "F.Fab")
		)
		(fp_line
			(start -0.12065 -0.305054)
			(end -0.12065 -0.2794)
			(stroke
				(width 0.1)
				(type default)
			)
			(layer "F.Fab")
		)
		(fp_line
			(start -0.67945 0.3048)
			(end -0.67945 -0.305054)
			(stroke
				(width 0.1)
				(type default)
			)
			(layer "F.Fab")
		)
		(fp_line
			(start -0.67945 -0.305054)
			(end -0.12065 -0.305054)
			(stroke
				(width 0.1)
				(type default)
			)
			(layer "F.Fab")
		)
		(pad "1" smd circle
			(at -0.40005 0 180)
			(size 0 0)
			(layers "F.Cu" "F.Mask" "F.Paste")
			(net "SVID_ALERT0_CPU0_R_N")
		)
		(pad "2" smd circle
			(at 0.40005 0 180)
			(size 0 0)
			(layers "F.Cu" "F.Mask" "F.Paste")
			(net "SVID_ALERT_PVCCINFAON_CPU0_R")
		)
	)
	(footprint ""
		(layer "F.Cu")
		(at 246.14505 -40.259762 90)
		(property "Reference" "PD112"
			(at 7.442454 -2.35839 0)
			(unlocked yes)
			(layer "F.SilkS")
			(effects
				(font
					(size 0.7874 0.5842)
					(thickness 0.1524)
				)
				(justify left)
			)
		)
		(property "Value" ""
			(at 0 0 90)
			(layer "F.Fab")
			(effects
				(font
					(size 1.27 1.27)
				)
			)
		)
		(duplicate_pad_numbers_are_jumpers no)
		(fp_line
			(start 4.107942 -1.459992)
			(end 4.107942 1.459992)
			(stroke
				(width 0.1524)
				(type default)
			)
			(layer "F.SilkS")
		)
		(fp_line
			(start -3.400044 -1.459992)
			(end 4.107942 -1.459992)
			(stroke
				(width 0.1524)
				(type default)
			)
			(layer "F.SilkS")
		)
		(fp_line
			(start 4.107942 1.459992)
			(end -3.400044 1.459992)
			(stroke
				(width 0.1524)
				(type default)
			)
			(layer "F.SilkS")
		)
		(fp_line
			(start -3.400044 1.459992)
			(end -3.400044 -1.459992)
			(stroke
				(width 0.1524)
				(type default)
			)
			(layer "F.SilkS")
		)
		(fp_rect
			(start 3.308096 -1.459992)
			(end 4.107942 1.459992)
			(stroke
				(width 0)
				(type default)
			)
			(fill yes)
			(layer "F.SilkS")
		)
		(fp_line
			(start 2.29997 -1.459992)
			(end 2.29997 1.459992)
			(stroke
				(width 0.1)
				(type default)
			)
			(layer "F.Fab")
		)
		(fp_line
			(start -2.29997 -1.459992)
			(end 2.29997 -1.459992)
			(stroke
				(width 0.1)
				(type default)
			)
			(layer "F.Fab")
		)
		(fp_line
			(start 2.29997 1.459992)
			(end -2.29997 1.459992)
			(stroke
				(width 0.1)
				(type default)
			)
			(layer "F.Fab")
		)
		(fp_line
			(start -2.29997 1.459992)
			(end -2.29997 -1.459992)
			(stroke
				(width 0.1)
				(type default)
			)
			(layer "F.Fab")
		)
		(fp_text user "+"
			(at -4.7752 -0.12065 90)
			(unlocked yes)
			(layer "F.SilkS")
			(effects
				(font
					(size 1.905 1.4224)
					(thickness 0.1524)
				)
				(justify left)
			)
		)
		(fp_text user "-"
			(at 5.4102 0.29845 270)
			(unlocked yes)
			(layer "F.SilkS")
			(effects
				(font
					(size 1.905 1.4224)
					(thickness 0.1524)
				)
				(justify left)
			)
		)
		(fp_text user "+"
			(at -4.7752 -0.12065 90)
			(unlocked yes)
			(layer "F.Fab")
			(effects
				(font
					(size 1.905 1.4224)
					(thickness 0.1524)
				)
				(justify left)
			)
		)
		(fp_text user "-"
			(at 5.4102 0.29845 270)
			(unlocked yes)
			(layer "F.Fab")
			(effects
				(font
					(size 1.905 1.4224)
					(thickness 0.1524)
				)
				(justify left)
			)
		)
		(pad "A" smd rect
			(at -1.999996 0 180)
			(size 1.7018 2.5146)
			(layers "F.Cu" "F.Mask" "F.Paste")
			(net "GND")
		)
		(pad "C" smd rect
			(at 1.999996 0 180)
			(size 1.7018 2.5146)
			(layers "F.Cu" "F.Mask" "F.Paste")
			(net "P12V_E1S_0")
		)
	)
	(footprint ""
		(layer "F.Cu")
		(at 492.16437 -470.73439)
		(property "Reference" "U1_BP"
			(at -0.18669 -3.567938 0)
			(unlocked yes)
			(layer "F.SilkS")
			(effects
				(font
					(size 0.7874 0.5842)
					(thickness 0.1524)
				)
				(justify left)
			)
		)
		(property "Value" ""
			(at 0 0 0)
			(layer "F.Fab")
			(effects
				(font
					(size 1.27 1.27)
				)
			)
		)
		(duplicate_pad_numbers_are_jumpers no)
		(pad "1" smd circle
			(at 0 0)
			(size 0.762 0.762)
			(layers "F.Cu" "F.Mask" "F.Paste")
			(net "Net_8487")
		)
	)
)
